# TIMECARD (Time Appliance Project (Time Card)) — schematic netlist excerpt (pin names and nets, part order shuffled) for the footprints in the layout excerpt that follows; sources: Cadence DE-HDL packaged netlist, KiCad conversion of R4006-B0001-02_R01.brd

TP185  TP_PIONT  pkg TP010CT020B030_PTH  page 25 : \1\ = IO_L23P_16

U39  NLASB3157DFT2G_SC88  pkg SOT363_V2  page 24
  B1  = NC
  GND  = SG
  B0  = FLASH_DQ2
  A  = FPGA_FLASH_DQ2
  VCC  = XP3R3V_FPGA
  \select\  = MUX2_SEL

(kicad_pcb
	(version 20260206)
	(generator "pcbnew")
	(generator_version "10.0")
	(general
		(thickness 1.6)
		(legacy_teardrops no)
	)
	(paper "A4")
	(title_block
		(title "timecard-production-celestica-r4006 — R4006-B0001-02_R01.brd")
		(comment 1 "Time Appliance Project (Time Card) / footprints 171-172 of 1113")
	)
	(layers
		(0 "F.Cu" signal "TOP")
		(4 "In1.Cu" signal "L02_GND1")
		(6 "In2.Cu" signal "L03_SIG1")
		(8 "In3.Cu" signal "L04_GND2")
		(10 "In4.Cu" signal "L05_VCC1")
		(12 "In5.Cu" signal "L06_VCC2")
		(14 "In6.Cu" signal "L07_GND3")
		(16 "In7.Cu" signal "L08_SIG2")
		(18 "In8.Cu" signal "L09_GND4")
		(2 "B.Cu" signal "BOTTOM")
		(9 "F.Adhes" user "F.Adhesive")
		(11 "B.Adhes" user "B.Adhesive")
		(13 "F.Paste" user "Package Geometry/Pastemask Top")
		(15 "B.Paste" user "Package Geometry/Pastemask Bottom")
		(5 "F.SilkS" user "Ref Des/Silkscreen Top")
		(7 "B.SilkS" user "Ref Des/Silkscreen Bottom")
		(1 "F.Mask" user "Board Geometry/Soldermask Top")
		(3 "B.Mask" user "Board Geometry/Soldermask Bottom")
		(17 "Dwgs.User" user "User.Drawings")
		(19 "Cmts.User" user "User.Comments")
		(21 "Eco1.User" user "User.Eco1")
		(23 "Eco2.User" user "User.Eco2")
		(25 "Edge.Cuts" user "Board Geometry/Outline")
		(27 "Margin" user)
		(31 "F.CrtYd" user "Package Geometry/Place Bound Top")
		(29 "B.CrtYd" user "Package Geometry/Place Bound Bottom")
		(35 "F.Fab" user "Ref Des/Assembly Top")
		(33 "B.Fab" user "Ref Des/Assembly Bottom")
	)
	(footprint ""
		(layer "F.Cu")
		(at 101.092 -87.4522 -90)
		(property "Reference" "U39"
			(at -2.7178 1.99263 90)
			(unlocked yes)
			(layer "F.SilkS")
			(effects
				(font
					(size 0.7874 0.5842)
					(thickness 0.1524)
				)
			)
		)
		(property "Value" ""
			(at 0 0 270)
			(layer "F.Fab")
			(effects
				(font
					(size 1.27 1.27)
				)
			)
		)
		(property "Device Type" "NLASB3157DFT2G_SC88-G223-10187A"
			(at 0.1524 2.168906 270)
			(unlocked yes)
			(layer "F.Fab")
			(hide yes)
			(effects
				(font
					(size 0.7874 0.5842)
					(thickness 0.000001)
				)
			)
		)
		(property "User Part Number" "PARTNUM*"
			(at 0.127 3.184906 270)
			(unlocked yes)
			(layer "Cmts.User")
			(hide yes)
			(effects
				(font
					(size 0.7874 0.5842)
					(thickness 0.000001)
				)
			)
		)
		(duplicate_pad_numbers_are_jumpers no)
		(fp_line
			(start -1.50876 1.354074)
			(end -1.50876 -1.354074)
			(stroke
				(width 0.1)
				(type default)
			)
			(layer "F.SilkS")
		)
		(fp_line
			(start 1.50876 1.354074)
			(end -1.50876 1.354074)
			(stroke
				(width 0.1)
				(type default)
			)
			(layer "F.SilkS")
		)
		(fp_line
			(start -1.50876 -1.354074)
			(end 1.50876 -1.354074)
			(stroke
				(width 0.1)
				(type default)
			)
			(layer "F.SilkS")
		)
		(fp_line
			(start 1.50876 -1.354074)
			(end 1.50876 1.354074)
			(stroke
				(width 0.1)
				(type default)
			)
			(layer "F.SilkS")
		)
		(fp_poly
			(pts
				(arc
					(start -2.159 -1.3716)
					(mid -2.159 -0.6096)
					(end -2.159 -1.3716)
				)
			)
			(stroke
				(width 0)
				(type default)
			)
			(fill yes)
			(layer "F.SilkS")
		)
		(fp_poly
			(pts
				(xy -1.76276 1.608074) (xy 1.76276 1.608074) (xy 1.76276 -1.608074) (xy -1.76276 -1.608074)
			)
			(stroke
				(width 0)
				(type default)
			)
			(fill no)
			(layer "F.CrtYd")
		)
		(fp_line
			(start -0.674878 1.100074)
			(end -0.674878 -1.100074)
			(stroke
				(width 0.1)
				(type default)
			)
			(layer "F.Fab")
		)
		(fp_line
			(start 0.674878 1.100074)
			(end -0.674878 1.100074)
			(stroke
				(width 0.1)
				(type default)
			)
			(layer "F.Fab")
		)
		(fp_line
			(start -0.674878 -1.100074)
			(end 0.674878 -1.100074)
			(stroke
				(width 0.1)
				(type default)
			)
			(layer "F.Fab")
		)
		(fp_line
			(start 0.674878 -1.100074)
			(end 0.674878 1.100074)
			(stroke
				(width 0.1)
				(type default)
			)
			(layer "F.Fab")
		)
		(fp_poly
			(pts
				(arc
					(start -2.159 -1.3716)
					(mid -2.159 -0.6096)
					(end -2.159 -1.3716)
				)
			)
			(stroke
				(width 0)
				(type default)
			)
			(fill yes)
			(layer "F.Fab")
		)
		(fp_text user "3"
			(at -0.83185 1.778 0)
			(unlocked yes)
			(layer "F.SilkS")
			(effects
				(font
					(size 0.635 0.4064)
					(thickness 0.1524)
				)
			)
		)
		(fp_text user "4"
			(at 2.08915 1.651 0)
			(unlocked yes)
			(layer "F.SilkS")
			(effects
				(font
					(size 0.635 0.4064)
					(thickness 0.1524)
				)
			)
		)
		(fp_text user "6"
			(at 2.08915 -1.651 0)
			(unlocked yes)
			(layer "F.SilkS")
			(effects
				(font
					(size 0.635 0.4064)
					(thickness 0.1524)
				)
			)
		)
		(fp_text user "4"
			(at 2.035048 0.924306 90)
			(unlocked yes)
			(layer "F.Fab")
			(effects
				(font
					(size 0.7874 0.5842)
					(thickness 0.1524)
				)
			)
		)
		(fp_text user "3"
			(at -1.995678 0.91313 90)
			(unlocked yes)
			(layer "F.Fab")
			(effects
				(font
					(size 0.7874 0.5842)
					(thickness 0.1524)
				)
			)
		)
		(fp_text user "6"
			(at 1.97104 -0.731774 90)
			(unlocked yes)
			(layer "F.Fab")
			(effects
				(font
					(size 0.7874 0.5842)
					(thickness 0.1524)
				)
			)
		)
		(pad "1" smd rect
			(at -0.94996 -0.649986 270)
			(size 0.6096 0.4318)
			(layers "F.Cu" "F.Mask" "F.Paste")
			(net "Net_787")
		)
		(pad "2" smd rect
			(at -0.94996 0 270)
			(size 0.6096 0.4318)
			(layers "F.Cu" "F.Mask" "F.Paste")
			(net "SG")
		)
		(pad "3" smd rect
			(at -0.94996 0.649986 270)
			(size 0.6096 0.4318)
			(layers "F.Cu" "F.Mask" "F.Paste")
			(net "FLASH_DQ2")
		)
		(pad "4" smd rect
			(at 0.94996 0.649986 270)
			(size 0.6096 0.4318)
			(layers "F.Cu" "F.Mask" "F.Paste")
			(net "FPGA_FLASH_DQ2")
		)
		(pad "5" smd rect
			(at 0.94996 0 270)
			(size 0.6096 0.4318)
			(layers "F.Cu" "F.Mask" "F.Paste")
			(net "XP3R3V_FPGA")
		)
		(pad "6" smd rect
			(at 0.94996 -0.649986 270)
			(size 0.6096 0.4318)
			(layers "F.Cu" "F.Mask" "F.Paste")
			(net "MUX2_SEL")
		)
	)
	(footprint ""
		(layer "F.Cu")
		(at 107.442 -59.7916)
		(property "Reference" "TP185"
			(at 2.82575 0.7874 90)
			(unlocked yes)
			(layer "F.SilkS")
			(effects
				(font
					(size 0.635 0.4064)
					(thickness 0.1524)
				)
				(justify left)
			)
		)
		(property "Value" ""
			(at 0 0 0)
			(layer "F.Fab")
			(effects
				(font
					(size 1.27 1.27)
				)
			)
		)
		(property "Device Type" "TP_PIONT-TP010CT020B030_PTH-TPA"
			(at -1.341882 0.996696 0)
			(unlocked yes)
			(layer "F.Fab")
			(hide yes)
			(effects
				(font
					(size 0.7874 0.5842)
					(thickness 0.1524)
				)
				(justify left)
			)
		)
		(duplicate_pad_numbers_are_jumpers no)
		(fp_poly
			(pts
				(arc
					(start 0.889 0)
					(mid -0.889 0)
					(end 0.889 0)
				)
			)
			(stroke
				(width 0)
				(type default)
			)
			(fill no)
			(layer "B.CrtYd")
		)
		(fp_poly
			(pts
				(arc
					(start 0.889 0)
					(mid -0.889 0)
					(end 0.889 0)
				)
			)
			(stroke
				(width 0)
				(type default)
			)
			(fill no)
			(layer "F.CrtYd")
		)
		(pad "1" thru_hole circle
			(at 0 0)
			(size 0.508 0.508)
			(drill 0.254)
			(layers "*.Cu" "*.Mask")
			(remove_unused_layers no)
			(net "IO_L23P_16")
			(clearance 0.1016)
			(padstack
				(mode front_inner_back)
				(layer "Inner"
					(shape circle)
					(size 0.508 0.508)
					(clearance 0.1016)
				)
				(layer "B.Cu"
					(shape circle)
					(size 0.762 0.762)
					(clearance -0.0254)
				)
			)
		)
	)
)
